(kicad_pcb
	(version 20240108)
	(generator "pcbnew")
	(generator_version "8.0")
	(general
		(thickness 1.62)
		(legacy_teardrops no)
	)
	(paper "A4")
	(title_block
		(title "Jetson Orin Baseboard")
		(date "2025-03-12")
		(rev "1.3.4")
		(company "Antmicro Ltd")
		(comment 1 "www.antmicro.com")
		(comment 9 "footprints 208-211 of 677")
	)
	(layers
		(0 "F.Cu" signal)
		(1 "In1.Cu" signal)
		(2 "In2.Cu" signal)
		(3 "In3.Cu" signal)
		(4 "In4.Cu" jumper)
		(5 "In5.Cu" signal)
		(6 "In6.Cu" signal)
		(31 "B.Cu" signal)
		(32 "B.Adhes" user "B.Adhesive")
		(33 "F.Adhes" user "F.Adhesive")
		(34 "B.Paste" user)
		(35 "F.Paste" user)
		(36 "B.SilkS" user "B.Silkscreen")
		(37 "F.SilkS" user "F.Silkscreen")
		(38 "B.Mask" user)
		(39 "F.Mask" user)
		(40 "Dwgs.User" user "User.Drawings")
		(41 "Cmts.User" user "User.Comments")
		(42 "Eco1.User" user "User.Eco1")
		(43 "Eco2.User" user "User.Eco2")
		(44 "Edge.Cuts" user)
		(45 "Margin" user)
		(46 "B.CrtYd" user "B.Courtyard")
		(47 "F.CrtYd" user "F.Courtyard")
		(48 "B.Fab" user)
		(49 "F.Fab" user)
	)
	(footprint "antmicro-footprints:Conn_Molex_PicoBlade_1x4_0533980471"
		(layer "F.Cu")
		(at 51.93 109.95 -90)
		(descr "Molex PicoBlade series connector, 53398-0471")
		(tags "connector Molex PicoBlade side entry")
		(property "Reference" "J10"
			(at -5.825 0.33 0)
			(layer "F.SilkS")
			(effects
				(font
					(size 0.7 0.7)
					(thickness 0.15)
				)
				(justify left bottom)
			)
		)
		(property "Value" "Molex_PicoBlade_1x4_0533980471"
			(at -5.8 3.7 -90)
			(layer "F.Fab")
			(effects
				(font
					(size 0.7 0.7)
					(thickness 0.15)
				)
				(justify left bottom)
			)
		)
		(property "Footprint" "antmicro-footprints:Conn_Molex_PicoBlade_1x4_0533980471"
			(at 0 0 -90)
			(layer "F.Fab")
			(hide yes)
			(effects
				(font
					(size 1.27 1.27)
					(thickness 0.15)
				)
			)
		)
		(property "Datasheet" "https://www.molex.com/molex/products/part-detail/pcb_headers/0533980471"
			(at 0 0 -90)
			(layer "F.Fab")
			(hide yes)
			(effects
				(font
					(size 1.27 1.27)
					(thickness 0.15)
				)
			)
		)
		(property "Author" "Antmicro"
			(at -58.02 161.88 0)
			(layer "F.Fab")
			(hide yes)
			(effects
				(font
					(size 1 1)
					(thickness 0.15)
				)
			)
		)
		(property "License" "Apache-2.0"
			(at -58.02 161.88 0)
			(layer "F.Fab")
			(hide yes)
			(effects
				(font
					(size 1 1)
					(thickness 0.15)
				)
			)
		)
		(property "MPN" "0533980471"
			(at -58.02 161.88 0)
			(layer "F.Fab")
			(hide yes)
			(effects
				(font
					(size 1 1)
					(thickness 0.15)
				)
			)
		)
		(property "Manufacturer" "Molex"
			(at -58.02 161.88 0)
			(layer "F.Fab")
			(hide yes)
			(effects
				(font
					(size 1 1)
					(thickness 0.15)
				)
			)
		)
		(sheetname "Peripherals")
		(sheetfile "peripherals.kicad_sch")
		(attr smd)
		(fp_line
			(start -3.117 2.209)
			(end 3.115 2.209)
			(stroke
				(width 0.15)
				(type solid)
			)
			(layer "F.SilkS")
		)
		(fp_line
			(start -3.485 -0.76)
			(end -3.485 -1.71)
			(stroke
				(width 0.15)
				(type solid)
			)
			(layer "F.SilkS")
		)
		(fp_line
			(start 3.483 -0.76)
			(end 3.483 -1.71)
			(stroke
				(width 0.15)
				(type solid)
			)
			(layer "F.SilkS")
		)
		(fp_line
			(start -3.485 -1.71)
			(end -2.536 -1.71)
			(stroke
				(width 0.15)
				(type solid)
			)
			(layer "F.SilkS")
		)
		(fp_line
			(start -2.536 -1.71)
			(end -2.536 -2.4)
			(stroke
				(width 0.15)
				(type solid)
			)
			(layer "F.SilkS")
		)
		(fp_line
			(start 3.483 -1.71)
			(end 2.535 -1.71)
			(stroke
				(width 0.15)
				(type solid)
			)
			(layer "F.SilkS")
		)
		(fp_rect
			(start -5.677 -2.601)
			(end 5.675 2.7)
			(stroke
				(width 0.05)
				(type solid)
			)
			(fill none)
			(layer "F.CrtYd")
		)
		(fp_line
			(start -4.875 2.1)
			(end -5.077 1.898)
			(stroke
				(width 0.15)
				(type solid)
			)
			(layer "F.Fab")
		)
		(fp_line
			(start -3.375 2.1)
			(end -4.875 2.1)
			(stroke
				(width 0.15)
				(type solid)
			)
			(layer "F.Fab")
		)
		(fp_line
			(start -3.375 2.1)
			(end 3.374 2.1)
			(stroke
				(width 0.15)
				(type solid)
			)
			(layer "F.Fab")
		)
		(fp_line
			(start 3.374 2.1)
			(end 4.873 2.1)
			(stroke
				(width 0.15)
				(type solid)
			)
			(layer "F.Fab")
		)
		(fp_line
			(start 4.873 2.1)
			(end 5.075 1.898)
			(stroke
				(width 0.15)
				(type solid)
			)
			(layer "F.Fab")
		)
		(fp_line
			(start -5.077 1.898)
			(end -5.077 0.099)
			(stroke
				(width 0.15)
				(type solid)
			)
			(layer "F.Fab")
		)
		(fp_line
			(start 5.075 1.898)
			(end 5.075 0.099)
			(stroke
				(width 0.15)
				(type solid)
			)
			(layer "F.Fab")
		)
		(fp_line
			(start -2.025 1.175)
			(end -1.726 1.175)
			(stroke
				(width 0.15)
				(type solid)
			)
			(layer "F.Fab")
		)
		(fp_line
			(start -1.726 1.175)
			(end -1.726 0.575)
			(stroke
				(width 0.15)
				(type solid)
			)
			(layer "F.Fab")
		)
		(fp_line
			(start -0.777 1.175)
			(end -0.476 1.175)
			(stroke
				(width 0.15)
				(type solid)
			)
			(layer "F.Fab")
		)
		(fp_line
			(start -0.476 1.175)
			(end -0.476 0.575)
			(stroke
				(width 0.15)
				(type solid)
			)
			(layer "F.Fab")
		)
		(fp_line
			(start 0.474 1.175)
			(end 0.775 1.175)
			(stroke
				(width 0.15)
				(type solid)
			)
			(layer "F.Fab")
		)
		(fp_line
			(start 0.775 1.175)
			(end 0.775 0.575)
			(stroke
				(width 0.15)
				(type solid)
			)
			(layer "F.Fab")
		)
		(fp_line
			(start 1.725 1.175)
			(end 2.023 1.175)
			(stroke
				(width 0.15)
				(type solid)
			)
			(layer "F.Fab")
		)
		(fp_line
			(start 2.023 1.175)
			(end 2.023 0.575)
			(stroke
				(width 0.15)
				(type solid)
			)
			(layer "F.Fab")
		)
		(fp_line
			(start -2.025 0.575)
			(end -2.025 1.175)
			(stroke
				(width 0.15)
				(type solid)
			)
			(layer "F.Fab")
		)
		(fp_line
			(start -1.726 0.575)
			(end -2.025 0.575)
			(stroke
				(width 0.15)
				(type solid)
			)
			(layer "F.Fab")
		)
		(fp_line
			(start -0.777 0.575)
			(end -0.777 1.175)
			(stroke
				(width 0.15)
				(type solid)
			)
			(layer "F.Fab")
		)
		(fp_line
			(start -0.476 0.575)
			(end -0.777 0.575)
			(stroke
				(width 0.15)
				(type solid)
			)
			(layer "F.Fab")
		)
		(fp_line
			(start 0.474 0.575)
			(end 0.474 1.175)
			(stroke
				(width 0.15)
				(type solid)
			)
			(layer "F.Fab")
		)
		(fp_line
			(start 0.775 0.575)
			(end 0.474 0.575)
			(stroke
				(width 0.15)
				(type solid)
			)
			(layer "F.Fab")
		)
		(fp_line
			(start 1.725 0.575)
			(end 1.725 1.175)
			(stroke
				(width 0.15)
				(type solid)
			)
			(layer "F.Fab")
		)
		(fp_line
			(start 2.023 0.575)
			(end 1.725 0.575)
			(stroke
				(width 0.15)
				(type solid)
			)
			(layer "F.Fab")
		)
		(fp_line
			(start -5.077 0.099)
			(end -4.875 -0.101)
			(stroke
				(width 0.15)
				(type solid)
			)
			(layer "F.Fab")
		)
		(fp_line
			(start 5.075 0.099)
			(end 4.873 -0.101)
			(stroke
				(width 0.15)
				(type solid)
			)
			(layer "F.Fab")
		)
		(fp_line
			(start -4.875 -0.101)
			(end -4.875 -0.701)
			(stroke
				(width 0.15)
				(type solid)
			)
			(layer "F.Fab")
		)
		(fp_line
			(start 4.873 -0.101)
			(end 4.873 -0.701)
			(stroke
				(width 0.15)
				(type solid)
			)
			(layer "F.Fab")
		)
		(fp_line
			(start -4.875 -0.701)
			(end -3.375 -0.701)
			(stroke
				(width 0.15)
				(type solid)
			)
			(layer "F.Fab")
		)
		(fp_line
			(start 4.873 -0.701)
			(end 3.374 -0.701)
			(stroke
				(width 0.15)
				(type solid)
			)
			(layer "F.Fab")
		)
		(fp_line
			(start -1.875 -0.893)
			(end -1.375 -1.601)
			(stroke
				(width 0.15)
				(type solid)
			)
			(layer "F.Fab")
		)
		(fp_line
			(start -3.375 -1.601)
			(end -3.375 2.1)
			(stroke
				(width 0.15)
				(type solid)
			)
			(layer "F.Fab")
		)
		(fp_line
			(start -3.375 -1.601)
			(end 3.374 -1.601)
			(stroke
				(width 0.15)
				(type solid)
			)
			(layer "F.Fab")
		)
		(fp_line
			(start -2.375 -1.601)
			(end -1.875 -0.893)
			(stroke
				(width 0.15)
				(type solid)
			)
			(layer "F.Fab")
		)
		(fp_line
			(start 3.374 -1.601)
			(end 3.374 2.1)
			(stroke
				(width 0.15)
				(type solid)
			)
			(layer "F.Fab")
		)
		(fp_text user "${REFERENCE}"
			(at -5.8 5.2 -90)
			(layer "F.Fab")
			(hide yes)
			(effects
				(font
					(size 0.7 0.7)
					(thickness 0.15)
				)
				(justify left bottom)
			)
		)
		(fp_text user "Author: Antmicro"
			(at -5.8 6.6 -90)
			(layer "F.Fab")
			(hide yes)
			(effects
				(font
					(size 0.7 0.7)
					(thickness 0.15)
				)
				(justify left bottom)
			)
		)
		(fp_text user "License: Apache-2.0"
			(at -5.8 8 -90)
			(layer "F.Fab")
			(hide yes)
			(effects
				(font
					(size 0.7 0.7)
					(thickness 0.15)
				)
				(justify left bottom)
			)
		)
		(pad "1" smd roundrect
			(at -1.875 -1.75 270)
			(size 0.8 1.3)
			(layers "F.Cu" "F.Paste" "F.Mask")
			(roundrect_rratio 0.25)
			(net 1 "GND")
			(pinfunction "1")
			(pintype "passive")
		)
		(pad "2" smd roundrect
			(at -0.625 -1.75 270)
			(size 0.8 1.3)
			(layers "F.Cu" "F.Paste" "F.Mask")
			(roundrect_rratio 0.25)
			(net 99 "+5V")
			(pinfunction "2")
			(pintype "passive")
		)
		(pad "3" smd roundrect
			(at 0.623 -1.75 270)
			(size 0.8 1.3)
			(layers "F.Cu" "F.Paste" "F.Mask")
			(roundrect_rratio 0.25)
			(net 541 "/Peripherals/FAN_TACH_5V")
			(pinfunction "3")
			(pintype "passive")
		)
		(pad "4" smd roundrect
			(at 1.874 -1.75 270)
			(size 0.8 1.3)
			(layers "F.Cu" "F.Paste" "F.Mask")
			(roundrect_rratio 0.25)
			(net 540 "/Peripherals/FAN_PWM_5V")
			(pinfunction "4")
			(pintype "passive")
		)
		(pad "MP1" smd roundrect
			(at -4.425 0.998 270)
			(size 2.1 3)
			(layers "F.Cu" "F.Paste" "F.Mask")
			(roundrect_rratio 0.119048)
			(net 726 "unconnected-(J10-PadMP1)")
			(pinfunction "MP1")
			(pintype "passive+no_connect")
		)
		(pad "MP2" smd roundrect
			(at 4.424 0.998 270)
			(size 2.1 3)
			(layers "F.Cu" "F.Paste" "F.Mask")
			(roundrect_rratio 0.119048)
			(net 727 "unconnected-(J10-PadMP2)")
			(pinfunction "MP2")
			(pintype "passive+no_connect")
		)
	)
	(footprint "antmicro-footprints:R_0402_1005Metric"
		(layer "F.Cu")
		(at 57.8 107.1)
		(descr "Resistor SMD 0402")
		(tags "resistor SMD 0402")
		(property "Reference" "R254"
			(at -3.7 0.15 0)
			(layer "F.SilkS")
			(effects
				(font
					(size 0.7 0.7)
					(thickness 0.15)
				)
				(justify left bottom)
			)
		)
		(property "Value" "R_10k_0402"
			(at 0 1.4 0)
			(layer "F.Fab")
			(effects
				(font
					(size 0.7 0.7)
					(thickness 0.15)
				)
				(justify left bottom)
			)
		)
		(property "Footprint" "antmicro-footprints:R_0402_1005Metric"
			(at 0 0 0)
			(layer "F.Fab")
			(hide yes)
			(effects
				(font
					(size 1.27 1.27)
					(thickness 0.15)
				)
			)
		)
		(property "Datasheet" "https://www.bourns.com/docs/product-datasheets/cr.pdf"
			(at 0 0 0)
			(layer "F.Fab")
			(hide yes)
			(effects
				(font
					(size 1.27 1.27)
					(thickness 0.15)
				)
			)
		)
		(property "Author" "Antmicro"
			(at 0 0 0)
			(layer "F.Fab")
			(hide yes)
			(effects
				(font
					(size 1 1)
					(thickness 0.15)
				)
			)
		)
		(property "License" "Apache-2.0"
			(at 0 0 0)
			(layer "F.Fab")
			(hide yes)
			(effects
				(font
					(size 1 1)
					(thickness 0.15)
				)
			)
		)
		(property "MPN" "CR0402-FX-1002GLF"
			(at 0 0 0)
			(layer "F.Fab")
			(hide yes)
			(effects
				(font
					(size 1 1)
					(thickness 0.15)
				)
			)
		)
		(property "Manufacturer" "Bourns"
			(at 0 0 0)
			(layer "F.Fab")
			(hide yes)
			(effects
				(font
					(size 1 1)
					(thickness 0.15)
				)
			)
		)
		(property "Tolerance" "1%"
			(at 0 0 0)
			(layer "F.Fab")
			(hide yes)
			(effects
				(font
					(size 1 1)
					(thickness 0.15)
				)
			)
		)
		(property "Val" "10k"
			(at 0 0 0)
			(layer "F.Fab")
			(hide yes)
			(effects
				(font
					(size 1 1)
					(thickness 0.15)
				)
			)
		)
		(sheetname "Supply")
		(sheetfile "supply.kicad_sch")
		(attr smd)
		(fp_rect
			(start -0.925 -0.47)
			(end 0.925 0.47)
			(stroke
				(width 0.05)
				(type default)
			)
			(fill none)
			(layer "F.CrtYd")
		)
		(fp_rect
			(start -0.5 -0.25)
			(end 0.5 0.25)
			(stroke
				(width 0.15)
				(type solid)
			)
			(fill none)
			(layer "F.Fab")
		)
		(fp_text user "License: Apache-2.0"
			(at -0.95 5.169 0)
			(layer "F.Fab")
			(hide yes)
			(effects
				(font
					(size 0.7 0.7)
					(thickness 0.15)
				)
				(justify left bottom)
			)
		)
		(fp_text user "${REFERENCE}"
			(at -0.95 3.168 0)
			(layer "F.Fab")
			(hide yes)
			(effects
				(font
					(size 0.7 0.7)
					(thickness 0.15)
				)
				(justify left bottom)
			)
		)
		(fp_text user "Author: Antmicro"
			(at -0.95 4.169 0)
			(layer "F.Fab")
			(hide yes)
			(effects
				(font
					(size 0.7 0.7)
					(thickness 0.15)
				)
				(justify left bottom)
			)
		)
		(pad "1" smd roundrect
			(at -0.48 0)
			(size 0.59 0.64)
			(layers "F.Cu" "F.Paste" "F.Mask")
			(roundrect_rratio 0.25)
			(net 1 "GND")
			(pintype "passive")
		)
		(pad "2" smd roundrect
			(at 0.48 0)
			(size 0.59 0.64)
			(layers "F.Cu" "F.Paste" "F.Mask")
			(roundrect_rratio 0.25)
			(net 630 "Net-(Q15-G)")
			(pintype "passive")
		)
	)
	(footprint "antmicro-footprints:R_0402_1005Metric"
		(layer "F.Cu")
		(at 38.2 103.7 180)
		(descr "Resistor SMD 0402")
		(tags "resistor SMD 0402")
		(property "Reference" "R199"
			(at 3.65 -0.4 180)
			(layer "F.SilkS")
			(effects
				(font
					(size 0.7 0.7)
					(thickness 0.15)
				)
				(justify left bottom)
			)
		)
		(property "Value" "R_470k_0402"
			(at 0 1.4 180)
			(layer "F.Fab")
			(effects
				(font
					(size 0.7 0.7)
					(thickness 0.15)
				)
				(justify left bottom)
			)
		)
		(property "Footprint" "antmicro-footprints:R_0402_1005Metric"
			(at 0 0 180)
			(layer "F.Fab")
			(hide yes)
			(effects
				(font
					(size 1.27 1.27)
					(thickness 0.15)
				)
			)
		)
		(property "Datasheet" "https://www.bourns.com/docs/product-datasheets/cr.pdf"
			(at 0 0 180)
			(layer "F.Fab")
			(hide yes)
			(effects
				(font
					(size 1.27 1.27)
					(thickness 0.15)
				)
			)
		)
		(property "Author" "Antmicro"
			(at 76.4 207.4 0)
			(layer "F.Fab")
			(hide yes)
			(effects
				(font
					(size 1 1)
					(thickness 0.15)
				)
			)
		)
		(property "License" "Apache-2.0"
			(at 76.4 207.4 0)
			(layer "F.Fab")
			(hide yes)
			(effects
				(font
					(size 1 1)
					(thickness 0.15)
				)
			)
		)
		(property "MPN" "CR0402-FX-4703GLF"
			(at 76.4 207.4 0)
			(layer "F.Fab")
			(hide yes)
			(effects
				(font
					(size 1 1)
					(thickness 0.15)
				)
			)
		)
		(property "Manufacturer" "Bourns"
			(at 76.4 207.4 0)
			(layer "F.Fab")
			(hide yes)
			(effects
				(font
					(size 1 1)
					(thickness 0.15)
				)
			)
		)
		(property "Tolerance" "1%"
			(at 76.4 207.4 0)
			(layer "F.Fab")
			(hide yes)
			(effects
				(font
					(size 1 1)
					(thickness 0.15)
				)
			)
		)
		(property "Val" "470k"
			(at 76.4 207.4 0)
			(layer "F.Fab")
			(hide yes)
			(effects
				(font
					(size 1 1)
					(thickness 0.15)
				)
			)
		)
		(sheetname "Ethernet")
		(sheetfile "ethernet.kicad_sch")
		(attr smd exclude_from_pos_files exclude_from_bom dnp)
		(fp_rect
			(start -0.925 -0.47)
			(end 0.925 0.47)
			(stroke
				(width 0.05)
				(type default)
			)
			(fill none)
			(layer "F.CrtYd")
		)
		(fp_rect
			(start -0.5 -0.25)
			(end 0.5 0.25)
			(stroke
				(width 0.15)
				(type solid)
			)
			(fill none)
			(layer "F.Fab")
		)
		(fp_text user "${REFERENCE}"
			(at -0.95 3.168 180)
			(layer "F.Fab")
			(hide yes)
			(effects
				(font
					(size 0.7 0.7)
					(thickness 0.15)
				)
				(justify left bottom)
			)
		)
		(fp_text user "Author: Antmicro"
			(at -0.95 4.169 180)
			(layer "F.Fab")
			(hide yes)
			(effects
				(font
					(size 0.7 0.7)
					(thickness 0.15)
				)
				(justify left bottom)
			)
		)
		(fp_text user "License: Apache-2.0"
			(at -0.95 5.169 180)
			(layer "F.Fab")
			(hide yes)
			(effects
				(font
					(size 0.7 0.7)
					(thickness 0.15)
				)
				(justify left bottom)
			)
		)
		(pad "1" smd roundrect
			(at -0.48 0 180)
			(size 0.59 0.64)
			(layers "F.Cu" "F.Paste" "F.Mask")
			(roundrect_rratio 0.25)
			(net 650 "/Ethernet/ULS-12_CTRL")
			(pintype "passive")
		)
		(pad "2" smd roundrect
			(at 0.48 0 180)
			(size 0.59 0.64)
			(layers "F.Cu" "F.Paste" "F.Mask")
			(roundrect_rratio 0.25)
			(net 105 "/Ethernet/VDD")
			(pintype "passive")
		)
	)
	(footprint "antmicro-footprints:R_0402_1005Metric"
		(layer "F.Cu")
		(at 105.2 115.8 -90)
		(descr "Resistor SMD 0402")
		(tags "resistor SMD 0402")
		(property "Reference" "R184"
			(at -0.89 -0.45 -90)
			(layer "F.SilkS")
			(effects
				(font
					(size 0.7 0.7)
					(thickness 0.15)
				)
				(justify left bottom)
			)
		)
		(property "Value" "R_1k_0402"
			(at 0 1.4 -90)
			(layer "F.Fab")
			(effects
				(font
					(size 0.7 0.7)
					(thickness 0.15)
				)
				(justify left bottom)
			)
		)
		(property "Footprint" "antmicro-footprints:R_0402_1005Metric"
			(at 0 0 -90)
			(layer "F.Fab")
			(hide yes)
			(effects
				(font
					(size 1.27 1.27)
					(thickness 0.15)
				)
			)
		)
		(property "Datasheet" "https://www.bourns.com/docs/product-datasheets/cr.pdf"
			(at 0 0 -90)
			(layer "F.Fab")
			(hide yes)
			(effects
				(font
					(size 1.27 1.27)
					(thickness 0.15)
				)
			)
		)
		(property "Author" "Antmicro"
			(at -10.6 221 0)
			(layer "F.Fab")
			(hide yes)
			(effects
				(font
					(size 1 1)
					(thickness 0.15)
				)
			)
		)
		(property "License" "Apache-2.0"
			(at -10.6 221 0)
			(layer "F.Fab")
			(hide yes)
			(effects
				(font
					(size 1 1)
					(thickness 0.15)
				)
			)
		)
		(property "MPN" "CR0402-FX-1001GLF"
			(at -10.6 221 0)
			(layer "F.Fab")
			(hide yes)
			(effects
				(font
					(size 1 1)
					(thickness 0.15)
				)
			)
		)
		(property "Manufacturer" "Bourns"
			(at -10.6 221 0)
			(layer "F.Fab")
			(hide yes)
			(effects
				(font
					(size 1 1)
					(thickness 0.15)
				)
			)
		)
		(property "Tolerance" "1%"
			(at -10.6 221 0)
			(layer "F.Fab")
			(hide yes)
			(effects
				(font
					(size 1 1)
					(thickness 0.15)
				)
			)
		)
		(property "Val" "1k"
			(at -10.6 221 0)
			(layer "F.Fab")
			(hide yes)
			(effects
				(font
					(size 1 1)
					(thickness 0.15)
				)
			)
		)
		(sheetname "USB3")
		(sheetfile "usb3.kicad_sch")
		(attr smd)
		(fp_rect
			(start -0.925 -0.47)
			(end 0.925 0.47)
			(stroke
				(width 0.05)
				(type default)
			)
			(fill none)
			(layer "F.CrtYd")
		)
		(fp_rect
			(start -0.5 -0.25)
			(end 0.5 0.25)
			(stroke
				(width 0.15)
				(type solid)
			)
			(fill none)
			(layer "F.Fab")
		)
		(fp_text user "${REFERENCE}"
			(at -0.95 3.168 -90)
			(layer "F.Fab")
			(hide yes)
			(effects
				(font
					(size 0.7 0.7)
					(thickness 0.15)
				)
				(justify left bottom)
			)
		)
		(fp_text user "License: Apache-2.0"
			(at -0.95 5.169 -90)
			(layer "F.Fab")
			(hide yes)
			(effects
				(font
					(size 0.7 0.7)
					(thickness 0.15)
				)
				(justify left bottom)
			)
		)
		(fp_text user "Author: Antmicro"
			(at -0.95 4.169 -90)
			(layer "F.Fab")
			(hide yes)
			(effects
				(font
					(size 0.7 0.7)
					(thickness 0.15)
				)
				(justify left bottom)
			)
		)
		(pad "1" smd roundrect
			(at -0.48 0 270)
			(size 0.59 0.64)
			(layers "F.Cu" "F.Paste" "F.Mask")
			(roundrect_rratio 0.25)
			(net 562 "USBC1_PEN")
			(pintype "passive")
		)
		(pad "2" smd roundrect
			(at 0.48 0 270)
			(size 0.59 0.64)
			(layers "F.Cu" "F.Paste" "F.Mask")
			(roundrect_rratio 0.25)
			(net 87 "+3V3")
			(pintype "passive")
		)
	)
)
